# T6G (Grand Teton) — schematic netlist excerpt (pin names and nets, part order shuffled) for the footprints in the layout excerpt that follows; sources: Cadence DE-HDL packaged netlist, KiCad conversion of 04192023_DAF0TMB3IC0_F0TG_MB_C_brd_V02_OCP.brd

C680  Q_CAP_DIFFBUS  DIFF BUS_0.22UF 6.3V 20% X6S  pkg C0201  page 67 : \1\ = P5E_CPU1_G1_TX_C_DN<14> ; \2\ = P5E_CPU1_G1_TX_DN<14>
R3729  Q_RES  2.2K 5% CHIP  pkg 0402LF  page 252 : A = P3V3_AUX ; B = SMB_LM75_2_3V3AUX_SCL
PC2139  Q_CAP  1UF 25V 10% X6S  pkg C0402  page 140 : A = P12V_AUX ; B = GND

(kicad_pcb
	(version 20260206)
	(generator "pcbnew")
	(generator_version "10.0")
	(general
		(thickness 1.6)
		(legacy_teardrops no)
	)
	(paper "A4")
	(title_block
		(title "04192023_DAF0TMB3IC0_F0TG_MB_C_brd_V02_OCP.brd")
		(comment 1 "Grand Teton / footprints 3753-3755 of 8354")
	)
	(layers
		(0 "F.Cu" signal "TOP")
		(4 "In1.Cu" signal "GND")
		(6 "In2.Cu" signal "IN1")
		(8 "In3.Cu" signal "GND1")
		(10 "In4.Cu" signal "IN2")
		(12 "In5.Cu" signal "GND2")
		(14 "In6.Cu" signal "IN3")
		(16 "In7.Cu" signal "GND3")
		(18 "In8.Cu" signal "VCC")
		(20 "In9.Cu" signal "VCC1")
		(22 "In10.Cu" signal "GND4")
		(24 "In11.Cu" signal "IN4")
		(26 "In12.Cu" signal "GND5")
		(28 "In13.Cu" signal "IN5")
		(30 "In14.Cu" signal "GND6")
		(32 "In15.Cu" signal "IN6")
		(34 "In16.Cu" signal "GND7")
		(2 "B.Cu" signal "BOTTOM")
		(9 "F.Adhes" user "F.Adhesive")
		(11 "B.Adhes" user "B.Adhesive")
		(13 "F.Paste" user "Package Geometry/Pastemask Top")
		(15 "B.Paste" user "Package Geometry/Pastemask Bottom")
		(5 "F.SilkS" user "Ref Des/Silkscreen Top")
		(7 "B.SilkS" user "Ref Des/Silkscreen Bottom")
		(1 "F.Mask" user "Board Geometry/Soldermask Top")
		(3 "B.Mask" user "Board Geometry/Soldermask Bottom")
		(17 "Dwgs.User" user "User.Drawings")
		(19 "Cmts.User" user "User.Comments")
		(21 "Eco1.User" user "User.Eco1")
		(23 "Eco2.User" user "User.Eco2")
		(25 "Edge.Cuts" user "Board Geometry/Outline")
		(27 "Margin" user)
		(31 "F.CrtYd" user "Package Geometry/Place Bound Top")
		(29 "B.CrtYd" user "Package Geometry/Place Bound Bottom")
		(35 "F.Fab" user "Ref Des/Assembly Top")
		(33 "B.Fab" user "Ref Des/Assembly Bottom")
	)
	(footprint ""
		(layer "F.Cu")
		(at 254.592836 -113.32845)
		(property "Reference" "R3729"
			(at 0 0 0)
			(layer "F.SilkS")
			(hide yes)
			(effects
				(font
					(size 1.27 1.27)
				)
			)
		)
		(property "Value" ""
			(at 0 0 0)
			(layer "F.Fab")
			(effects
				(font
					(size 1.27 1.27)
				)
			)
		)
		(duplicate_pad_numbers_are_jumpers no)
		(fp_line
			(start -0.7874 -0.4064)
			(end 0.7874 -0.4064)
			(stroke
				(width 0.1524)
				(type default)
			)
			(layer "F.SilkS")
		)
		(fp_line
			(start -0.7874 0.4064)
			(end -0.7874 -0.4064)
			(stroke
				(width 0.1524)
				(type default)
			)
			(layer "F.SilkS")
		)
		(fp_line
			(start 0.7874 -0.4064)
			(end 0.7874 0.4064)
			(stroke
				(width 0.1524)
				(type default)
			)
			(layer "F.SilkS")
		)
		(fp_line
			(start 0.7874 0.4064)
			(end -0.7874 0.4064)
			(stroke
				(width 0.1524)
				(type default)
			)
			(layer "F.SilkS")
		)
		(fp_line
			(start -0.67945 -0.305054)
			(end -0.12065 -0.305054)
			(stroke
				(width 0.1)
				(type default)
			)
			(layer "F.Fab")
		)
		(fp_line
			(start -0.67945 0.3048)
			(end -0.67945 -0.305054)
			(stroke
				(width 0.1)
				(type default)
			)
			(layer "F.Fab")
		)
		(fp_line
			(start -0.12065 -0.305054)
			(end -0.12065 -0.2794)
			(stroke
				(width 0.1)
				(type default)
			)
			(layer "F.Fab")
		)
		(fp_line
			(start -0.12065 -0.2794)
			(end 0.12065 -0.2794)
			(stroke
				(width 0.1)
				(type default)
			)
			(layer "F.Fab")
		)
		(fp_line
			(start -0.12065 0.2794)
			(end -0.12065 0.3048)
			(stroke
				(width 0.1)
				(type default)
			)
			(layer "F.Fab")
		)
		(fp_line
			(start -0.12065 0.3048)
			(end -0.67945 0.3048)
			(stroke
				(width 0.1)
				(type default)
			)
			(layer "F.Fab")
		)
		(fp_line
			(start 0.120396 0.2794)
			(end -0.12065 0.2794)
			(stroke
				(width 0.1)
				(type default)
			)
			(layer "F.Fab")
		)
		(fp_line
			(start 0.120396 0.3048)
			(end 0.120396 0.2794)
			(stroke
				(width 0.1)
				(type default)
			)
			(layer "F.Fab")
		)
		(fp_line
			(start 0.12065 -0.3048)
			(end 0.67945 -0.3048)
			(stroke
				(width 0.1)
				(type default)
			)
			(layer "F.Fab")
		)
		(fp_line
			(start 0.12065 -0.2794)
			(end 0.12065 -0.3048)
			(stroke
				(width 0.1)
				(type default)
			)
			(layer "F.Fab")
		)
		(fp_line
			(start 0.67945 -0.3048)
			(end 0.67945 0.3048)
			(stroke
				(width 0.1)
				(type default)
			)
			(layer "F.Fab")
		)
		(fp_line
			(start 0.67945 0.3048)
			(end 0.120396 0.3048)
			(stroke
				(width 0.1)
				(type default)
			)
			(layer "F.Fab")
		)
		(pad "1" smd circle
			(at -0.40005 0)
			(size 0 0)
			(layers "F.Cu" "F.Mask" "F.Paste")
			(net "P3V3_AUX")
		)
		(pad "2" smd circle
			(at 0.40005 0)
			(size 0 0)
			(layers "F.Cu" "F.Mask" "F.Paste")
			(net "SMB_LM75_2_3V3AUX_SCL")
		)
	)
	(footprint ""
		(layer "F.Cu")
		(at 18.302478 -17.623536 90)
		(property "Reference" "C680"
			(at 0 0 90)
			(layer "F.SilkS")
			(hide yes)
			(effects
				(font
					(size 1.27 1.27)
				)
			)
		)
		(property "Value" ""
			(at 0 0 90)
			(layer "F.Fab")
			(effects
				(font
					(size 1.27 1.27)
				)
			)
		)
		(duplicate_pad_numbers_are_jumpers no)
		(fp_line
			(start 0.299974 -0.150114)
			(end 0.299974 0.150114)
			(stroke
				(width 0.1)
				(type default)
			)
			(layer "F.Fab")
		)
		(fp_line
			(start -0.299974 -0.150114)
			(end 0.299974 -0.150114)
			(stroke
				(width 0.1)
				(type default)
			)
			(layer "F.Fab")
		)
		(fp_line
			(start 0.299974 0.150114)
			(end -0.299974 0.150114)
			(stroke
				(width 0.1)
				(type default)
			)
			(layer "F.Fab")
		)
		(fp_line
			(start -0.299974 0.150114)
			(end -0.299974 -0.150114)
			(stroke
				(width 0.1)
				(type default)
			)
			(layer "F.Fab")
		)
		(pad "1" smd rect
			(at -0.2667 0 90)
			(size 0.3048 0.381)
			(layers "F.Cu" "F.Mask" "F.Paste")
			(net "P5E_CPU1_G1_TX_C_DN<14>")
		)
		(pad "2" smd rect
			(at 0.2667 0 90)
			(size 0.3048 0.381)
			(layers "F.Cu" "F.Mask" "F.Paste")
			(net "P5E_CPU1_G1_TX_DN<14>")
		)
	)
	(footprint ""
		(layer "F.Cu")
		(at 76.53401 -24.713946 -90)
		(property "Reference" "PC2139"
			(at 0 0 270)
			(layer "F.SilkS")
			(hide yes)
			(effects
				(font
					(size 1.27 1.27)
				)
			)
		)
		(property "Value" ""
			(at 0 0 270)
			(layer "F.Fab")
			(effects
				(font
					(size 1.27 1.27)
				)
			)
		)
		(duplicate_pad_numbers_are_jumpers no)
		(fp_line
			(start -0.7874 0.4064)
			(end -0.7874 -0.4064)
			(stroke
				(width 0.1524)
				(type default)
			)
			(layer "F.SilkS")
		)
		(fp_line
			(start 0.7874 0.4064)
			(end -0.7874 0.4064)
			(stroke
				(width 0.1524)
				(type default)
			)
			(layer "F.SilkS")
		)
		(fp_line
			(start -0.7874 -0.4064)
			(end 0.7874 -0.4064)
			(stroke
				(width 0.1524)
				(type default)
			)
			(layer "F.SilkS")
		)
		(fp_line
			(start 0.7874 -0.4064)
			(end 0.7874 0.4064)
			(stroke
				(width 0.1524)
				(type default)
			)
			(layer "F.SilkS")
		)
		(fp_line
			(start -0.67945 0.3048)
			(end -0.67945 -0.305054)
			(stroke
				(width 0.1)
				(type default)
			)
			(layer "F.Fab")
		)
		(fp_line
			(start -0.12065 0.3048)
			(end -0.67945 0.3048)
			(stroke
				(width 0.1)
				(type default)
			)
			(layer "F.Fab")
		)
		(fp_line
			(start 0.120396 0.3048)
			(end 0.120396 0.2794)
			(stroke
				(width 0.1)
				(type default)
			)
			(layer "F.Fab")
		)
		(fp_line
			(start 0.67945 0.3048)
			(end 0.120396 0.3048)
			(stroke
				(width 0.1)
				(type default)
			)
			(layer "F.Fab")
		)
		(fp_line
			(start -0.12065 0.2794)
			(end -0.12065 0.3048)
			(stroke
				(width 0.1)
				(type default)
			)
			(layer "F.Fab")
		)
		(fp_line
			(start 0.120396 0.2794)
			(end -0.12065 0.2794)
			(stroke
				(width 0.1)
				(type default)
			)
			(layer "F.Fab")
		)
		(fp_line
			(start -0.12065 -0.2794)
			(end 0.12065 -0.2794)
			(stroke
				(width 0.1)
				(type default)
			)
			(layer "F.Fab")
		)
		(fp_line
			(start 0.12065 -0.2794)
			(end 0.12065 -0.3048)
			(stroke
				(width 0.1)
				(type default)
			)
			(layer "F.Fab")
		)
		(fp_line
			(start 0.12065 -0.3048)
			(end 0.67945 -0.3048)
			(stroke
				(width 0.1)
				(type default)
			)
			(layer "F.Fab")
		)
		(fp_line
			(start 0.67945 -0.3048)
			(end 0.67945 0.3048)
			(stroke
				(width 0.1)
				(type default)
			)
			(layer "F.Fab")
		)
		(fp_line
			(start -0.67945 -0.305054)
			(end -0.12065 -0.305054)
			(stroke
				(width 0.1)
				(type default)
			)
			(layer "F.Fab")
		)
		(fp_line
			(start -0.12065 -0.305054)
			(end -0.12065 -0.2794)
			(stroke
				(width 0.1)
				(type default)
			)
			(layer "F.Fab")
		)
		(pad "1" smd circle
			(at -0.40005 0 270)
			(size 0 0)
			(layers "F.Cu" "F.Mask" "F.Paste")
			(net "P12V_AUX")
		)
		(pad "2" smd circle
			(at 0.40005 0 270)
			(size 0 0)
			(layers "F.Cu" "F.Mask" "F.Paste")
			(net "GND")
		)
	)
)
